(kicad_pcb
	(version 20260206)
	(generator "pcbnew")
	(generator_version "10.0")
	(general
		(thickness 1.21888)
		(legacy_teardrops no)
	)
	(paper "A4")
	(title_block
		(title "timecard-v8 — TimeCard-DC-V8_EXP.PcbDoc")
		(comment 1 "Time Appliance Project (Time Card) / footprints 175-177 of 288")
	)
	(layers
		(0 "F.Cu" signal "TOP")
		(4 "In1.Cu" signal "SGND")
		(6 "In2.Cu" signal "IN1")
		(8 "In3.Cu" signal "IN2")
		(10 "In4.Cu" signal "SGND1")
		(2 "B.Cu" signal "BOTTOM")
		(9 "F.Adhes" user "F.Adhesive")
		(11 "B.Adhes" user "B.Adhesive")
		(13 "F.Paste" user "Top Paste")
		(15 "B.Paste" user "Bottom Paste")
		(5 "F.SilkS" user "Top Overlay")
		(7 "B.SilkS" user "Bottom Overlay")
		(1 "F.Mask" user "Top Solder")
		(3 "B.Mask" user "Bottom Solder")
		(17 "Dwgs.User" user "User.Drawings")
		(19 "Cmts.User" user "User.Comments")
		(21 "Eco1.User" user "User.Eco1")
		(23 "Eco2.User" user "User.Eco2")
		(25 "Edge.Cuts" user)
		(27 "Margin" user)
		(31 "F.CrtYd" user "Top Courtyard")
		(29 "B.CrtYd" user "Bottom Courtyard")
		(35 "F.Fab" user "Top Component Center")
		(33 "B.Fab" user "Bottom Component Center")
	)
	(footprint "FPGA_CONN:SingleFPGAConn"
		(layer "F.Cu")
		(at 197.33851 104.56486 180)
		(property "Reference" "J34"
			(at 1.54101 -22.624409 180)
			(unlocked yes)
			(layer "F.SilkS")
			(effects
				(font
					(size 0.762 0.762)
					(thickness 0.2286)
				)
			)
		)
		(property "Value" "Single FPGA Conn"
			(at 9.25452 3.621231 180)
			(unlocked yes)
			(layer "F.SilkS")
			(hide yes)
			(effects
				(font
					(size 0.762 0.762)
					(thickness 0.2286)
				)
			)
		)
		(sheetname "FPGA")
		(sheetfile "FPGA.kicad_sch")
		(duplicate_pad_numbers_are_jumpers no)
		(fp_line
			(start 2 0.70003)
			(end 1.40005 1.24994)
			(stroke
				(width 0.15011)
				(type solid)
			)
			(layer "F.SilkS")
		)
		(fp_line
			(start 2 0.03302)
			(end 2 0.70003)
			(stroke
				(width 0.15011)
				(type solid)
			)
			(layer "F.SilkS")
		)
		(fp_line
			(start 2 -20.69998)
			(end 2 -20.03298)
			(stroke
				(width 0.15011)
				(type solid)
			)
			(layer "F.SilkS")
		)
		(fp_line
			(start 2 -20.69998)
			(end 1.40005 -21.24989)
			(stroke
				(width 0.15011)
				(type solid)
			)
			(layer "F.SilkS")
		)
		(fp_line
			(start 1.40005 1.24994)
			(end -1.40005 1.24994)
			(stroke
				(width 0.15011)
				(type solid)
			)
			(layer "F.SilkS")
		)
		(fp_line
			(start 1.40005 -21.24989)
			(end -1.40005 -21.24989)
			(stroke
				(width 0.15011)
				(type solid)
			)
			(layer "F.SilkS")
		)
		(fp_line
			(start -1.40005 0.70003)
			(end -1.40005 1.24994)
			(stroke
				(width 0.15011)
				(type solid)
			)
			(layer "F.SilkS")
		)
		(fp_line
			(start -1.40005 0.70003)
			(end -2 0.70003)
			(stroke
				(width 0.15011)
				(type solid)
			)
			(layer "F.SilkS")
		)
		(fp_line
			(start -1.40005 -20.69998)
			(end -2 -20.69998)
			(stroke
				(width 0.15011)
				(type solid)
			)
			(layer "F.SilkS")
		)
		(fp_line
			(start -1.40005 -21.24989)
			(end -1.40005 -20.69998)
			(stroke
				(width 0.15011)
				(type solid)
			)
			(layer "F.SilkS")
		)
		(fp_line
			(start -2 0.03302)
			(end -2 0.70003)
			(stroke
				(width 0.15011)
				(type solid)
			)
			(layer "F.SilkS")
		)
		(fp_line
			(start -2 -20.69998)
			(end -2 -20.03298)
			(stroke
				(width 0.15011)
				(type solid)
			)
			(layer "F.SilkS")
		)
		(fp_circle
			(center 3.5052 -0.22453)
			(end 3.5052 -0.02438)
			(stroke
				(width 0.40005)
				(type solid)
			)
			(fill no)
			(layer "F.SilkS")
		)
		(pad "1" smd rect
			(at 2.02489 -0.24993 180)
			(size 1.54991 0.24994)
			(layers "F.Cu" "F.Mask" "F.Paste")
			(net "+5.0V")
		)
		(pad "2" smd rect
			(at -2.02489 -0.24993 180)
			(size 1.54991 0.24994)
			(layers "F.Cu" "F.Mask" "F.Paste")
			(net "+5.0V")
		)
		(pad "3" smd rect
			(at 2.02489 -0.75006 180)
			(size 1.54991 0.24994)
			(layers "F.Cu" "F.Mask" "F.Paste")
			(net "+5.0V")
		)
		(pad "4" smd rect
			(at -2.02489 -0.75006 180)
			(size 1.54991 0.24994)
			(layers "F.Cu" "F.Mask" "F.Paste")
			(net "+5.0V")
		)
		(pad "5" smd rect
			(at 2.02489 -1.24993 180)
			(size 1.54991 0.24994)
			(layers "F.Cu" "F.Mask" "F.Paste")
			(net "+5.0V")
		)
		(pad "6" smd rect
			(at -2.02489 -1.24993 180)
			(size 1.54991 0.24994)
			(layers "F.Cu" "F.Mask" "F.Paste")
			(net "+5.0V")
		)
		(pad "7" smd rect
			(at 2.02489 -1.75006 180)
			(size 1.54991 0.24994)
			(layers "F.Cu" "F.Mask" "F.Paste")
			(net "+5.0V")
		)
		(pad "8" smd rect
			(at -2.02489 -1.75006 180)
			(size 1.54991 0.24994)
			(layers "F.Cu" "F.Mask" "F.Paste")
			(net "+5.0V")
		)
		(pad "9" smd rect
			(at 2.02489 -2.24993 180)
			(size 1.54991 0.24994)
			(layers "F.Cu" "F.Mask" "F.Paste")
			(net "GND")
		)
		(pad "10" smd rect
			(at -2.02489 -2.24993 180)
			(size 1.54991 0.24994)
			(layers "F.Cu" "F.Mask" "F.Paste")
			(net "GND")
		)
		(pad "11" smd rect
			(at 2.02489 -2.75006 180)
			(size 1.54991 0.24994)
			(layers "F.Cu" "F.Mask" "F.Paste")
		)
		(pad "12" smd rect
			(at -2.02489 -2.75006 180)
			(size 1.54991 0.24994)
			(layers "F.Cu" "F.Mask" "F.Paste")
		)
		(pad "13" smd rect
			(at 2.02489 -3.24993 180)
			(size 1.54991 0.24994)
			(layers "F.Cu" "F.Mask" "F.Paste")
		)
		(pad "14" smd rect
			(at -2.02489 -3.24993 180)
			(size 1.54991 0.24994)
			(layers "F.Cu" "F.Mask" "F.Paste")
		)
		(pad "15" smd rect
			(at 2.02489 -3.75005 180)
			(size 1.54991 0.24994)
			(layers "F.Cu" "F.Mask" "F.Paste")
		)
		(pad "16" smd rect
			(at -2.02489 -3.75005 180)
			(size 1.54991 0.24994)
			(layers "F.Cu" "F.Mask" "F.Paste")
		)
		(pad "17" smd rect
			(at 2.02489 -4.24993 180)
			(size 1.54991 0.24994)
			(layers "F.Cu" "F.Mask" "F.Paste")
		)
		(pad "18" smd rect
			(at -2.02489 -4.24993 180)
			(size 1.54991 0.24994)
			(layers "F.Cu" "F.Mask" "F.Paste")
		)
		(pad "19" smd rect
			(at 2.02489 -4.75005 180)
			(size 1.54991 0.24994)
			(layers "F.Cu" "F.Mask" "F.Paste")
			(net "GND")
		)
		(pad "20" smd rect
			(at -2.02489 -4.75005 180)
			(size 1.54991 0.24994)
			(layers "F.Cu" "F.Mask" "F.Paste")
			(net "GND")
		)
		(pad "21" smd rect
			(at 2.02489 -5.24992 180)
			(size 1.54991 0.24994)
			(layers "F.Cu" "F.Mask" "F.Paste")
		)
		(pad "22" smd rect
			(at -2.02489 -5.24992 180)
			(size 1.54991 0.24994)
			(layers "F.Cu" "F.Mask" "F.Paste")
			(net "GPS1_RST")
		)
		(pad "23" smd rect
			(at 2.02489 -5.75005 180)
			(size 1.54991 0.24994)
			(layers "F.Cu" "F.Mask" "F.Paste")
		)
		(pad "24" smd rect
			(at -2.02489 -5.75005 180)
			(size 1.54991 0.24994)
			(layers "F.Cu" "F.Mask" "F.Paste")
		)
		(pad "25" smd rect
			(at 2.02489 -6.24992 180)
			(size 1.54991 0.24994)
			(layers "F.Cu" "F.Mask" "F.Paste")
		)
		(pad "26" smd rect
			(at -2.02489 -6.24992 180)
			(size 1.54991 0.24994)
			(layers "F.Cu" "F.Mask" "F.Paste")
		)
		(pad "27" smd rect
			(at 2.02489 -6.75005 180)
			(size 1.54991 0.24994)
			(layers "F.Cu" "F.Mask" "F.Paste")
		)
		(pad "28" smd rect
			(at -2.02489 -6.75005 180)
			(size 1.54991 0.24994)
			(layers "F.Cu" "F.Mask" "F.Paste")
		)
		(pad "29" smd rect
			(at 2.02489 -7.24992 180)
			(size 1.54991 0.24994)
			(layers "F.Cu" "F.Mask" "F.Paste")
			(net "GND")
		)
		(pad "30" smd rect
			(at -2.02489 -7.24992 180)
			(size 1.54991 0.24994)
			(layers "F.Cu" "F.Mask" "F.Paste")
			(net "GND")
		)
		(pad "31" smd rect
			(at 2.02489 -7.75005 180)
			(size 1.54991 0.24994)
			(layers "F.Cu" "F.Mask" "F.Paste")
		)
		(pad "32" smd rect
			(at -2.02489 -7.75005 180)
			(size 1.54991 0.24994)
			(layers "F.Cu" "F.Mask" "F.Paste")
			(net "GPS1_TP1")
		)
		(pad "33" smd rect
			(at 2.02489 -8.24992 180)
			(size 1.54991 0.24994)
			(layers "F.Cu" "F.Mask" "F.Paste")
		)
		(pad "34" smd rect
			(at -2.02489 -8.24992 180)
			(size 1.54991 0.24994)
			(layers "F.Cu" "F.Mask" "F.Paste")
			(net "GPS1_TP2")
		)
		(pad "35" smd rect
			(at 2.02489 -8.75004 180)
			(size 1.54991 0.24994)
			(layers "F.Cu" "F.Mask" "F.Paste")
		)
		(pad "36" smd rect
			(at -2.02489 -8.75004 180)
			(size 1.54991 0.24994)
			(layers "F.Cu" "F.Mask" "F.Paste")
		)
		(pad "37" smd rect
			(at 2.02489 -9.24992 180)
			(size 1.54991 0.24994)
			(layers "F.Cu" "F.Mask" "F.Paste")
		)
		(pad "38" smd rect
			(at -2.02489 -9.24992 180)
			(size 1.54991 0.24994)
			(layers "F.Cu" "F.Mask" "F.Paste")
		)
		(pad "39" smd rect
			(at 2.02489 -9.75004 180)
			(size 1.54991 0.24994)
			(layers "F.Cu" "F.Mask" "F.Paste")
			(net "GND")
		)
		(pad "40" smd rect
			(at -2.02489 -9.75004 180)
			(size 1.54991 0.24994)
			(layers "F.Cu" "F.Mask" "F.Paste")
			(net "GND")
		)
		(pad "41" smd rect
			(at 2.02489 -10.24991 180)
			(size 1.54991 0.24994)
			(layers "F.Cu" "F.Mask" "F.Paste")
		)
		(pad "42" smd rect
			(at -2.02489 -10.24991 180)
			(size 1.54991 0.24994)
			(layers "F.Cu" "F.Mask" "F.Paste")
		)
		(pad "43" smd rect
			(at 2.02489 -10.75004 180)
			(size 1.54991 0.24994)
			(layers "F.Cu" "F.Mask" "F.Paste")
		)
		(pad "44" smd rect
			(at -2.02489 -10.75004 180)
			(size 1.54991 0.24994)
			(layers "F.Cu" "F.Mask" "F.Paste")
			(net "EXT_EEPROM_WP")
		)
		(pad "45" smd rect
			(at 2.02489 -11.24991 180)
			(size 1.54991 0.24994)
			(layers "F.Cu" "F.Mask" "F.Paste")
		)
		(pad "46" smd rect
			(at -2.02489 -11.24991 180)
			(size 1.54991 0.24994)
			(layers "F.Cu" "F.Mask" "F.Paste")
		)
		(pad "47" smd rect
			(at 2.02489 -11.75004 180)
			(size 1.54991 0.24994)
			(layers "F.Cu" "F.Mask" "F.Paste")
		)
		(pad "48" smd rect
			(at -2.02489 -11.75004 180)
			(size 1.54991 0.24994)
			(layers "F.Cu" "F.Mask" "F.Paste")
		)
		(pad "49" smd rect
			(at 2.02489 -12.24991 180)
			(size 1.54991 0.24994)
			(layers "F.Cu" "F.Mask" "F.Paste")
			(net "GND")
		)
		(pad "50" smd rect
			(at -2.02489 -12.24991 180)
			(size 1.54991 0.24994)
			(layers "F.Cu" "F.Mask" "F.Paste")
			(net "GND")
		)
		(pad "51" smd rect
			(at 2.02489 -12.75004 180)
			(size 1.54991 0.24994)
			(layers "F.Cu" "F.Mask" "F.Paste")
		)
		(pad "52" smd rect
			(at -2.02489 -12.75004 180)
			(size 1.54991 0.24994)
			(layers "F.Cu" "F.Mask" "F.Paste")
		)
		(pad "53" smd rect
			(at 2.02489 -13.24991 180)
			(size 1.54991 0.24994)
			(layers "F.Cu" "F.Mask" "F.Paste")
		)
		(pad "54" smd rect
			(at -2.02489 -13.24991 180)
			(size 1.54991 0.24994)
			(layers "F.Cu" "F.Mask" "F.Paste")
		)
		(pad "55" smd rect
			(at 2.02489 -13.75003 180)
			(size 1.54991 0.24994)
			(layers "F.Cu" "F.Mask" "F.Paste")
		)
		(pad "56" smd rect
			(at -2.02489 -13.75003 180)
			(size 1.54991 0.24994)
			(layers "F.Cu" "F.Mask" "F.Paste")
		)
		(pad "57" smd rect
			(at 2.02489 -14.24991 180)
			(size 1.54991 0.24994)
			(layers "F.Cu" "F.Mask" "F.Paste")
		)
		(pad "58" smd rect
			(at -2.02489 -14.24991 180)
			(size 1.54991 0.24994)
			(layers "F.Cu" "F.Mask" "F.Paste")
		)
		(pad "59" smd rect
			(at 2.02489 -14.75003 180)
			(size 1.54991 0.24994)
			(layers "F.Cu" "F.Mask" "F.Paste")
			(net "GND")
		)
		(pad "60" smd rect
			(at -2.02489 -14.75003 180)
			(size 1.54991 0.24994)
			(layers "F.Cu" "F.Mask" "F.Paste")
			(net "GND")
		)
		(pad "61" smd rect
			(at 2.02489 -15.2499 180)
			(size 1.54991 0.24994)
			(layers "F.Cu" "F.Mask" "F.Paste")
		)
		(pad "62" smd rect
			(at -2.02489 -15.2499 180)
			(size 1.54991 0.24994)
			(layers "F.Cu" "F.Mask" "F.Paste")
		)
		(pad "63" smd rect
			(at 2.02489 -15.75003 180)
			(size 1.54991 0.24994)
			(layers "F.Cu" "F.Mask" "F.Paste")
		)
		(pad "64" smd rect
			(at -2.02489 -15.75003 180)
			(size 1.54991 0.24994)
			(layers "F.Cu" "F.Mask" "F.Paste")
		)
		(pad "65" smd rect
			(at 2.02489 -16.2499 180)
			(size 1.54991 0.24994)
			(layers "F.Cu" "F.Mask" "F.Paste")
		)
		(pad "66" smd rect
			(at -2.02489 -16.2499 180)
			(size 1.54991 0.24994)
			(layers "F.Cu" "F.Mask" "F.Paste")
		)
		(pad "67" smd rect
			(at 2.02489 -16.75003 180)
			(size 1.54991 0.24994)
			(layers "F.Cu" "F.Mask" "F.Paste")
			(net "KEY2")
		)
		(pad "68" smd rect
			(at -2.02489 -16.75003 180)
			(size 1.54991 0.24994)
			(layers "F.Cu" "F.Mask" "F.Paste")
		)
		(pad "69" smd rect
			(at 2.02489 -17.2499 180)
			(size 1.54991 0.24994)
			(layers "F.Cu" "F.Mask" "F.Paste")
			(net "GND")
		)
		(pad "70" smd rect
			(at -2.02489 -17.2499 180)
			(size 1.54991 0.24994)
			(layers "F.Cu" "F.Mask" "F.Paste")
			(net "GND")
		)
		(pad "71" smd rect
			(at 2.02489 -17.75003 180)
			(size 1.54991 0.24994)
			(layers "F.Cu" "F.Mask" "F.Paste")
			(net "LED4")
		)
		(pad "72" smd rect
			(at -2.02489 -17.75003 180)
			(size 1.54991 0.24994)
			(layers "F.Cu" "F.Mask" "F.Paste")
		)
		(pad "73" smd rect
			(at 2.02489 -18.2499 180)
			(size 1.54991 0.24994)
			(layers "F.Cu" "F.Mask" "F.Paste")
			(net "LED3")
		)
		(pad "74" smd rect
			(at -2.02489 -18.2499 180)
			(size 1.54991 0.24994)
			(layers "F.Cu" "F.Mask" "F.Paste")
		)
		(pad "75" smd rect
			(at 2.02489 -18.75002 180)
			(size 1.54991 0.24994)
			(layers "F.Cu" "F.Mask" "F.Paste")
			(net "LED2")
		)
		(pad "76" smd rect
			(at -2.02489 -18.75002 180)
			(size 1.54991 0.24994)
			(layers "F.Cu" "F.Mask" "F.Paste")
		)
		(pad "77" smd rect
			(at 2.02489 -19.2499 180)
			(size 1.54991 0.24994)
			(layers "F.Cu" "F.Mask" "F.Paste")
			(net "LED1")
		)
		(pad "78" smd rect
			(at -2.02489 -19.2499 180)
			(size 1.54991 0.24994)
			(layers "F.Cu" "F.Mask" "F.Paste")
		)
		(pad "79" smd rect
			(at 2.02489 -19.75002 180)
			(size 1.54991 0.24994)
			(layers "F.Cu" "F.Mask" "F.Paste")
		)
		(pad "80" smd rect
			(at -2.02489 -19.75002 180)
			(size 1.54991 0.24994)
			(layers "F.Cu" "F.Mask" "F.Paste")
		)
		(pad "81" smd rect
			(at 0.01135 1.17626 180)
			(size 1.70002 1.35001)
			(layers "F.Cu" "F.Mask" "F.Paste")
		)
		(pad "82" thru_hole circle
			(at 0 0 180)
			(size 0.55016 0.55016)
			(drill 0.55016)
			(layers "*.Cu" "*.Mask")
			(remove_unused_layers no)
			(thermal_bridge_angle 90)
		)
		(pad "83" thru_hole circle
			(at 0 -19.99996 180)
			(size 0.55016 0.55016)
			(drill 0.55016)
			(layers "*.Cu" "*.Mask")
			(remove_unused_layers no)
			(thermal_bridge_angle 90)
		)
		(pad "84" smd rect
			(at 0.01135 -21.17374 180)
			(size 1.70002 1.35001)
			(layers "F.Cu" "F.Mask" "F.Paste")
		)
	)
	(footprint "SA53:SolderSocket"
		(layer "F.Cu")
		(at 128.7781 138.2162 90)
		(property "Reference" "SKT8"
			(at -3.426921 0.8766 0)
			(unlocked yes)
			(layer "F.SilkS")
			(effects
				(font
					(size 0.762 0.762)
					(thickness 0.2286)
				)
			)
		)
		(property "Value" "0332-0-43-80-18-27-10-0"
			(at -2.910071 16.1362 0)
			(unlocked yes)
			(layer "F.SilkS")
			(hide yes)
			(effects
				(font
					(size 0.762 0.762)
					(thickness 0.2286)
				)
			)
		)
		(sheetname "MAC")
		(sheetfile "MAC.kicad_sch")
		(duplicate_pad_numbers_are_jumpers no)
		(pad "1" thru_hole circle
			(at 0 0 90)
			(size 2.54 2.54)
			(drill 2.0066)
			(layers "*.Cu" "*.Mask")
			(remove_unused_layers no)
			(net "MAC_PPS_IN")
			(thermal_bridge_angle 90)
		)
	)
	(footprint "SamacSys:SOP50P310X90-8N"
		(layer "F.Cu")
		(at 82.3761 122.3662 180)
		(property "Reference" "U11"
			(at 0.153605 2.026921 180)
			(unlocked yes)
			(layer "F.SilkS")
			(effects
				(font
					(size 0.762 0.762)
					(thickness 0.2286)
				)
			)
		)
		(property "Value" "NC7WV125K8X"
			(at 6.207715 2.884671 180)
			(unlocked yes)
			(layer "F.SilkS")
			(hide yes)
			(effects
				(font
					(size 0.762 0.762)
					(thickness 0.2286)
				)
			)
		)
		(sheetname "USER_IO")
		(sheetfile "USER_IO.kicad_sch")
		(duplicate_pad_numbers_are_jumpers no)
		(fp_line
			(start 0.8 1)
			(end -0.8 1)
			(stroke
				(width 0.2)
				(type solid)
			)
			(layer "F.SilkS")
		)
		(fp_line
			(start 0.8 -1)
			(end 0.8 1)
			(stroke
				(width 0.2)
				(type solid)
			)
			(layer "F.SilkS")
		)
		(fp_line
			(start 0.8 -1)
			(end -0.8 -1)
			(stroke
				(width 0.2)
				(type solid)
			)
			(layer "F.SilkS")
		)
		(fp_line
			(start -0.8 -1)
			(end -0.8 1)
			(stroke
				(width 0.2)
				(type solid)
			)
			(layer "F.SilkS")
		)
		(fp_line
			(start -1.15 -1.25)
			(end -2 -1.25)
			(stroke
				(width 0.2)
				(type solid)
			)
			(layer "F.SilkS")
		)
		(pad "1" smd rect
			(at -1.575 -0.75 180)
			(size 0.85 0.3)
			(layers "F.Cu" "F.Mask" "F.Paste")
			(net "ANT3_IO_OUT")
		)
		(pad "2" smd rect
			(at -1.575 -0.25 180)
			(size 0.85 0.3)
			(layers "F.Cu" "F.Mask" "F.Paste")
			(net "ANT3_OUT")
		)
		(pad "3" smd rect
			(at -1.575 0.25 180)
			(size 0.85 0.3)
			(layers "F.Cu" "F.Mask" "F.Paste")
			(net "ANT3_IN")
		)
		(pad "4" smd rect
			(at -1.575 0.75 180)
			(size 0.85 0.3)
			(layers "F.Cu" "F.Mask" "F.Paste")
			(net "GND")
		)
		(pad "5" smd rect
			(at 1.575 0.75 180)
			(size 0.85 0.3)
			(layers "F.Cu" "F.Mask" "F.Paste")
			(net "NetR28_1")
		)
		(pad "6" smd rect
			(at 1.575 0.25 180)
			(size 0.85 0.3)
			(layers "F.Cu" "F.Mask" "F.Paste")
			(net "NetR28_1")
		)
		(pad "7" smd rect
			(at 1.575 -0.25 180)
			(size 0.85 0.3)
			(layers "F.Cu" "F.Mask" "F.Paste")
			(net "ANT3_IO_IN")
		)
		(pad "8" smd rect
			(at 1.575 -0.75 180)
			(size 0.85 0.3)
			(layers "F.Cu" "F.Mask" "F.Paste")
			(net "+3.3V")
		)
	)
)
